FILE_TYPE = CONNECTIVITY;
{Allegro Design Entry HDL 17.4-2019 S026 (4007227) 1/17/2022}
"PAGE_NUMBER" = 57;
0"NC";
1"PVDD18_S5_P1\g";
2"P1V5_BAT\g";
3"PVDDCR_CPU0_P1\g";
4"PVDDCR_CPU0_P1\g";
5"PVDDCR_CPU1_P1\g";
6"PVDDCR_CPU1_P1\g";
7"PVDDIO_P1\g";
8"PVDD11_S3_P1\g";
9"PVDD18_S5_P1\g";
10"PVDD_33_S5\g";
11"PVDDCR_SOC_P1\g";
12"PVDDCR_SOC_P1\g";
13"CPU1_VDDBT_RTC_G";
%"VCC_CORE"
"1","(-7425,6600)","0","pure_quanta_power","I27";
;
HDL_POWER"PVDDCR_CPU0_P1"
CDS_LIB"pure_quanta_power";
"A"3;
%"VCC_CORE"
"1","(-8875,6600)","0","pure_quanta_power","I28";
;
HDL_POWER"PVDDCR_CPU0_P1"
CDS_LIB"pure_quanta_power";
"A"4;
%"GENOA_SP5"
"24","(-8150,3350)","0","pure_quanta","I29";
;
LOCATION"U26"
$SEC"24"
CDS_SEC"24"
VALUE"SOCKET6096_13568-001"
PART_TYPE"SMLF"
MATERIAL"IO"
NEEDS_NO_SIZE"TRUE"
CDS_LMAN_SYM_OUTLINE"-500,3150,500,-3150"
CDS_LIB"pure_quanta"
PART_NUMBER"DGA^6000030";
"VDDCR_CPU0_AU33"
$PN"AU33"3;
"VDDCR_CPU0_AU25"
$PN"AU25"3;
"VDDCR_CPU0_AU48"
$PN"AU48"3;
"VDDCR_CPU0_AU44"
$PN"AU44"3;
"VDDCR_CPU0_AU29"
$PN"AU29"3;
"VDDCR_CPU0_AT49"
$PN"AT49"3;
"VDDCR_CPU0_AU46"
$PN"AU46"3;
"VDDCR_CPU0_AU42"
$PN"AU42"3;
"VDDCR_CPU0_Y35"
$PN"Y35"3;
"VDDCR_CPU0_Y36"
$PN"Y36"3;
"VDDCR_CPU0_Y40"
$PN"Y40"3;
"VDDCR_CPU0_Y41"
$PN"Y41"3;
"VDDCR_CPU0_AB23"
$PN"AB23"3;
"VDDCR_CPU0_AB24"
$PN"AB24"3;
"VDDCR_CPU0_AB26"
$PN"AB26"3;
"VDDCR_CPU0_AB27"
$PN"AB27"3;
"VDDCR_CPU0_AB29"
$PN"AB29"3;
"VDDCR_CPU0_AB30"
$PN"AB30"3;
"VDDCR_CPU0_AB32"
$PN"AB32"3;
"VDDCR_CPU0_AB33"
$PN"AB33"3;
"VDDCR_CPU0_AB43"
$PN"AB43"3;
"VDDCR_CPU0_AB44"
$PN"AB44"3;
"VDDCR_CPU0_AB46"
$PN"AB46"3;
"VDDCR_CPU0_AB47"
$PN"AB47"3;
"VDDCR_CPU0_AB49"
$PN"AB49"3;
"VDDCR_CPU0_AB50"
$PN"AB50"3;
"VDDCR_CPU0_AB52"
$PN"AB52"3;
"VDDCR_CPU0_AB53"
$PN"AB53"3;
"VDDCR_CPU0_AC35"
$PN"AC35"3;
"VDDCR_CPU0_AC36"
$PN"AC36"3;
"VDDCR_CPU0_AC40"
$PN"AC40"3;
"VDDCR_CPU0_AC41"
$PN"AC41"3;
"VDDCR_CPU0_AF23"
$PN"AF23"3;
"VDDCR_CPU0_AF24"
$PN"AF24"3;
"VDDCR_CPU0_AF26"
$PN"AF26"3;
"VDDCR_CPU0_AF27"
$PN"AF27"3;
"VDDCR_CPU0_AF29"
$PN"AF29"3;
"VDDCR_CPU0_AF30"
$PN"AF30"3;
"VDDCR_CPU0_AF32"
$PN"AF32"3;
"VDDCR_CPU0_AF33"
$PN"AF33"3;
"VDDCR_CPU0_AF43"
$PN"AF43"3;
"VDDCR_CPU0_AF44"
$PN"AF44"3;
"VDDCR_CPU0_AF46"
$PN"AF46"3;
"VDDCR_CPU0_AF47"
$PN"AF47"3;
"VDDCR_CPU0_AF49"
$PN"AF49"3;
"VDDCR_CPU0_AF50"
$PN"AF50"3;
"VDDCR_CPU0_AF52"
$PN"AF52"3;
"VDDCR_CPU0_AF53"
$PN"AF53"3;
"VDDCR_CPU0_AG35"
$PN"AG35"3;
"VDDCR_CPU0_AG36"
$PN"AG36"3;
"VDDCR_CPU0_AG40"
$PN"AG40"3;
"VDDCR_CPU0_AG41"
$PN"AG41"3;
"VDDCR_CPU0_AK23"
$PN"AK23"3;
"VDDCR_CPU0_AK24"
$PN"AK24"3;
"VDDCR_CPU0_AK26"
$PN"AK26"3;
"VDDCR_CPU0_AK27"
$PN"AK27"3;
"VDDCR_CPU0_AK29"
$PN"AK29"3;
"VDDCR_CPU0_AK30"
$PN"AK30"3;
"VDDCR_CPU0_AK32"
$PN"AK32"3;
"VDDCR_CPU0_AK33"
$PN"AK33"3;
"VDDCR_CPU0_AK43"
$PN"AK43"3;
"VDDCR_CPU0_AK44"
$PN"AK44"3;
"VDDCR_CPU0_AK46"
$PN"AK46"3;
"VDDCR_CPU0_AK47"
$PN"AK47"3;
"VDDCR_CPU0_AK49"
$PN"AK49"3;
"VDDCR_CPU0_AK50"
$PN"AK50"3;
"VDDCR_CPU0_AK52"
$PN"AK52"3;
"VDDCR_CPU0_AK53"
$PN"AK53"3;
"VDDCR_CPU0_AL35"
$PN"AL35"3;
"VDDCR_CPU0_AL36"
$PN"AL36"3;
"VDDCR_CPU0_AL40"
$PN"AL40"3;
"VDDCR_CPU0_AL41"
$PN"AL41"3;
"VDDCR_CPU0_AP23"
$PN"AP23"3;
"VDDCR_CPU0_AP24"
$PN"AP24"3;
"VDDCR_CPU0_AP26"
$PN"AP26"3;
"VDDCR_CPU0_AP27"
$PN"AP27"3;
"VDDCR_CPU0_AP29"
$PN"AP29"3;
"VDDCR_CPU0_AP30"
$PN"AP30"3;
"VDDCR_CPU0_AP32"
$PN"AP32"3;
"VDDCR_CPU0_AP33"
$PN"AP33"3;
"VDDCR_CPU0_AP43"
$PN"AP43"3;
"VDDCR_CPU0_AP44"
$PN"AP44"3;
"VDDCR_CPU0_AP46"
$PN"AP46"3;
"VDDCR_CPU0_AP47"
$PN"AP47"3;
"VDDCR_CPU0_AP49"
$PN"AP49"3;
"VDDCR_CPU0_AP50"
$PN"AP50"3;
"VDDCR_CPU0_AP52"
$PN"AP52"3;
"VDDCR_CPU0_AP53"
$PN"AP53"3;
"VDDCR_CPU0_AR23"
$PN"AR23"3;
"VDDCR_CPU0_AR25"
$PN"AR25"3;
"VDDCR_CPU0_AR27"
$PN"AR27"3;
"VDDCR_CPU0_AR29"
$PN"AR29"3;
"VDDCR_CPU0_AR31"
$PN"AR31"3;
"VDDCR_CPU0_AR33"
$PN"AR33"3;
"VDDCR_CPU0_AR35"
$PN"AR35"3;
"VDDCR_CPU0_AR40"
$PN"AR40"3;
"VDDCR_CPU0_AR42"
$PN"AR42"3;
"VDDCR_CPU0_AR44"
$PN"AR44"3;
"VDDCR_CPU0_AR46"
$PN"AR46"3;
"VDDCR_CPU0_AR48"
$PN"AR48"3;
"VDDCR_CPU0_AR50"
$PN"AR50"3;
"VDDCR_CPU0_AT24"
$PN"AT24"3;
"VDDCR_CPU0_AT26"
$PN"AT26"3;
"VDDCR_CPU0_AT28"
$PN"AT28"3;
"VDDCR_CPU0_AT30"
$PN"AT30"3;
"VDDCR_CPU0_AT32"
$PN"AT32"3;
"VDDCR_CPU0_AT34"
$PN"AT34"3;
"VDDCR_CPU0_AT36"
$PN"AT36"3;
"VDDCR_CPU0_AT39"
$PN"AT39"3;
"VDDCR_CPU0_AT41"
$PN"AT41"3;
"VDDCR_CPU0_AT43"
$PN"AT43"3;
"VDDCR_CPU0_AT45"
$PN"AT45"3;
"VDDCR_CPU0_AT47"
$PN"AT47"3;
"VDDCR_CPU0_B19"
$PN"B19"4;
"VDDCR_CPU0_B20"
$PN"B20"4;
"VDDCR_CPU0_B22"
$PN"B22"4;
"VDDCR_CPU0_B23"
$PN"B23"4;
"VDDCR_CPU0_B25"
$PN"B25"4;
"VDDCR_CPU0_B26"
$PN"B26"4;
"VDDCR_CPU0_B28"
$PN"B28"4;
"VDDCR_CPU0_B29"
$PN"B29"4;
"VDDCR_CPU0_B31"
$PN"B31"4;
"VDDCR_CPU0_B32"
$PN"B32"4;
"VDDCR_CPU0_B34"
$PN"B34"4;
"VDDCR_CPU0_B35"
$PN"B35"4;
"VDDCR_CPU0_B41"
$PN"B41"4;
"VDDCR_CPU0_B42"
$PN"B42"4;
"VDDCR_CPU0_B44"
$PN"B44"4;
"VDDCR_CPU0_B45"
$PN"B45"4;
"VDDCR_CPU0_B47"
$PN"B47"4;
"VDDCR_CPU0_B48"
$PN"B48"4;
"VDDCR_CPU0_B50"
$PN"B50"4;
"VDDCR_CPU0_B51"
$PN"B51"4;
"VDDCR_CPU0_B53"
$PN"B53"4;
"VDDCR_CPU0_B54"
$PN"B54"4;
"VDDCR_CPU0_B56"
$PN"B56"4;
"VDDCR_CPU0_B57"
$PN"B57"4;
"VDDCR_CPU0_C20"
$PN"C20"4;
"VDDCR_CPU0_D55"
$PN"D55"4;
"VDDCR_CPU0_D56"
$PN"D56"4;
"VDDCR_CPU0_E22"
$PN"E22"4;
"VDDCR_CPU0_E25"
$PN"E25"4;
"VDDCR_CPU0_E28"
$PN"E28"4;
"VDDCR_CPU0_E31"
$PN"E31"4;
"VDDCR_CPU0_E34"
$PN"E34"4;
"VDDCR_CPU0_E35"
$PN"E35"4;
"VDDCR_CPU0_E42"
$PN"E42"4;
"VDDCR_CPU0_E45"
$PN"E45"4;
"VDDCR_CPU0_E48"
$PN"E48"4;
"VDDCR_CPU0_E51"
$PN"E51"4;
"VDDCR_CPU0_E54"
$PN"E54"4;
"VDDCR_CPU0_F22"
$PN"F22"4;
"VDDCR_CPU0_F25"
$PN"F25"4;
"VDDCR_CPU0_F28"
$PN"F28"4;
"VDDCR_CPU0_F31"
$PN"F31"4;
"VDDCR_CPU0_F34"
$PN"F34"4;
"VDDCR_CPU0_F42"
$PN"F42"4;
"VDDCR_CPU0_F45"
$PN"F45"4;
"VDDCR_CPU0_F48"
$PN"F48"4;
"VDDCR_CPU0_F51"
$PN"F51"4;
"VDDCR_CPU0_F54"
$PN"F54"4;
"VDDCR_CPU0_G35"
$PN"G35"4;
"VDDCR_CPU0_G36"
$PN"G36"4;
"VDDCR_CPU0_G40"
$PN"G40"4;
"VDDCR_CPU0_G41"
$PN"G41"4;
"VDDCR_CPU0_H23"
$PN"H23"4;
"VDDCR_CPU0_H24"
$PN"H24"4;
"VDDCR_CPU0_H26"
$PN"H26"4;
"VDDCR_CPU0_H27"
$PN"H27"4;
"VDDCR_CPU0_H29"
$PN"H29"4;
"VDDCR_CPU0_H30"
$PN"H30"4;
"VDDCR_CPU0_H32"
$PN"H32"4;
"VDDCR_CPU0_H33"
$PN"H33"4;
"VDDCR_CPU0_H43"
$PN"H43"4;
"VDDCR_CPU0_H44"
$PN"H44"4;
"VDDCR_CPU0_H46"
$PN"H46"4;
"VDDCR_CPU0_H47"
$PN"H47"4;
"VDDCR_CPU0_H49"
$PN"H49"4;
"VDDCR_CPU0_H50"
$PN"H50"4;
"VDDCR_CPU0_H52"
$PN"H52"4;
"VDDCR_CPU0_H53"
$PN"H53"4;
"VDDCR_CPU0_J35"
$PN"J35"4;
"VDDCR_CPU0_J36"
$PN"J36"4;
"VDDCR_CPU0_J40"
$PN"J40"4;
"VDDCR_CPU0_J41"
$PN"J41"4;
"VDDCR_CPU0_M23"
$PN"M23"4;
"VDDCR_CPU0_M24"
$PN"M24"4;
"VDDCR_CPU0_M26"
$PN"M26"4;
"VDDCR_CPU0_M27"
$PN"M27"4;
"VDDCR_CPU0_M29"
$PN"M29"4;
"VDDCR_CPU0_M30"
$PN"M30"4;
"VDDCR_CPU0_M32"
$PN"M32"4;
"VDDCR_CPU0_M33"
$PN"M33"4;
"VDDCR_CPU0_M43"
$PN"M43"4;
"VDDCR_CPU0_M44"
$PN"M44"4;
"VDDCR_CPU0_M46"
$PN"M46"4;
"VDDCR_CPU0_M47"
$PN"M47"4;
"VDDCR_CPU0_M49"
$PN"M49"4;
"VDDCR_CPU0_M50"
$PN"M50"4;
"VDDCR_CPU0_M52"
$PN"M52"4;
"VDDCR_CPU0_M53"
$PN"M53"4;
"VDDCR_CPU0_N35"
$PN"N35"4;
"VDDCR_CPU0_N36"
$PN"N36"4;
"VDDCR_CPU0_N40"
$PN"N40"4;
"VDDCR_CPU0_N41"
$PN"N41"4;
"VDDCR_CPU0_T23"
$PN"T23"4;
"VDDCR_CPU0_T24"
$PN"T24"4;
"VDDCR_CPU0_T26"
$PN"T26"4;
"VDDCR_CPU0_T27"
$PN"T27"4;
"VDDCR_CPU0_T29"
$PN"T29"4;
"VDDCR_CPU0_T30"
$PN"T30"4;
"VDDCR_CPU0_T32"
$PN"T32"4;
"VDDCR_CPU0_T33"
$PN"T33"4;
"VDDCR_CPU0_T43"
$PN"T43"4;
"VDDCR_CPU0_T44"
$PN"T44"4;
"VDDCR_CPU0_T46"
$PN"T46"4;
"VDDCR_CPU0_T47"
$PN"T47"4;
"VDDCR_CPU0_T49"
$PN"T49"4;
"VDDCR_CPU0_T50"
$PN"T50"4;
"VDDCR_CPU0_T52"
$PN"T52"4;
"VDDCR_CPU0_T53"
$PN"T53"4;
"VDDCR_CPU0_U35"
$PN"U35"4;
"VDDCR_CPU0_U36"
$PN"U36"4;
"VDDCR_CPU0_U40"
$PN"U40"4;
"VDDCR_CPU0_U41"
$PN"U41"4;
"VDDCR_CPU0_W29"
$PN"W29"4;
"VDDCR_CPU0_W30"
$PN"W30"4;
"VDDCR_CPU0_W32"
$PN"W32"4;
"VDDCR_CPU0_W33"
$PN"W33"4;
"VDDCR_CPU0_W43"
$PN"W43"3;
"VDDCR_CPU0_W44"
$PN"W44"3;
"VDDCR_CPU0_W46"
$PN"W46"3;
"VDDCR_CPU0_W47"
$PN"W47"3;
%"VCC_CORE"
"1","(-5525,6550)","0","pure_quanta_power","I30";
;
HDL_POWER"PVDDCR_CPU1_P1"
CDS_LIB"pure_quanta_power";
"A"5;
%"VCC_CORE"
"1","(-6950,6325)","0","pure_quanta_power","I31";
;
HDL_POWER"PVDDCR_CPU1_P1"
CDS_LIB"pure_quanta_power";
"A"6;
%"GENOA_SP5"
"25","(-6225,3375)","0","pure_quanta","I32";
;
LOCATION"U26"
$SEC"25"
CDS_SEC"25"
VALUE"SOCKET6096_13568-001"
MATERIAL"IO"
PART_TYPE"SMLF"
NEEDS_NO_SIZE"TRUE"
CDS_LMAN_SYM_OUTLINE"-500,3200,500,-3200"
CDS_LIB"pure_quanta"
PART_NUMBER"DGA^6000030";
"VDDCR_CPU1_BN46"
$PN"BN46"5;
"VDDCR_CPU1_BN35"
$PN"BN35"5;
"VDDCR_CPU1_BN27"
$PN"BN27"5;
"VDDCR_CPU1_BP32"
$PN"BP32"5;
"VDDCR_CPU1_BP28"
$PN"BP28"5;
"VDDCR_CPU1_BP24"
$PN"BP24"5;
"VDDCR_CPU1_DH51"
$PN"DH51"5;
"VDDCR_CPU1_DH50"
$PN"DH50"5;
"VDDCR_CPU1_DH48"
$PN"DH48"5;
"VDDCR_CPU1_DH47"
$PN"DH47"5;
"VDDCR_CPU1_DH45"
$PN"DH45"5;
"VDDCR_CPU1_DH57"
$PN"DH57"5;
"VDDCR_CPU1_DH56"
$PN"DH56"5;
"VDDCR_CPU1_DH54"
$PN"DH54"5;
"VDDCR_CPU1_DH53"
$PN"DH53"5;
"VDDCR_CPU1_DH44"
$PN"DH44"5;
"VDDCR_CPU1_DH42"
$PN"DH42"5;
"VDDCR_CPU1_DH41"
$PN"DH41"5;
"VDDCR_CPU1_DH35"
$PN"DH35"5;
"VDDCR_CPU1_DH34"
$PN"DH34"5;
"VDDCR_CPU1_DH32"
$PN"DH32"5;
"VDDCR_CPU1_DH31"
$PN"DH31"5;
"VDDCR_CPU1_DH29"
$PN"DH29"5;
"VDDCR_CPU1_DH28"
$PN"DH28"5;
"VDDCR_CPU1_DH26"
$PN"DH26"5;
"VDDCR_CPU1_DH25"
$PN"DH25"5;
"VDDCR_CPU1_DH23"
$PN"DH23"5;
"VDDCR_CPU1_DH22"
$PN"DH22"5;
"VDDCR_CPU1_DH20"
$PN"DH20"5;
"VDDCR_CPU1_DH19"
$PN"DH19"5;
"VDDCR_CPU1_DG57"
$PN"DG57"5;
"VDDCR_CPU1_DG19"
$PN"DG19"5;
"VDDCR_CPU1_DE54"
$PN"DE54"5;
"VDDCR_CPU1_DE51"
$PN"DE51"5;
"VDDCR_CPU1_DE48"
$PN"DE48"5;
"VDDCR_CPU1_DE45"
$PN"DE45"5;
"VDDCR_CPU1_DE42"
$PN"DE42"5;
"VDDCR_CPU1_DE41"
$PN"DE41"5;
"VDDCR_CPU1_DE35"
$PN"DE35"5;
"VDDCR_CPU1_DE34"
$PN"DE34"5;
"VDDCR_CPU1_DE31"
$PN"DE31"5;
"VDDCR_CPU1_DE28"
$PN"DE28"5;
"VDDCR_CPU1_DE25"
$PN"DE25"5;
"VDDCR_CPU1_DE22"
$PN"DE22"5;
"VDDCR_CPU1_DD54"
$PN"DD54"5;
"VDDCR_CPU1_DD51"
$PN"DD51"5;
"VDDCR_CPU1_DD48"
$PN"DD48"5;
"VDDCR_CPU1_DD45"
$PN"DD45"5;
"VDDCR_CPU1_DD42"
$PN"DD42"5;
"VDDCR_CPU1_DD34"
$PN"DD34"5;
"VDDCR_CPU1_DD31"
$PN"DD31"5;
"VDDCR_CPU1_DD28"
$PN"DD28"5;
"VDDCR_CPU1_DD25"
$PN"DD25"5;
"VDDCR_CPU1_DD22"
$PN"DD22"5;
"VDDCR_CPU1_DC41"
$PN"DC41"5;
"VDDCR_CPU1_DC40"
$PN"DC40"5;
"VDDCR_CPU1_DC36"
$PN"DC36"5;
"VDDCR_CPU1_DC35"
$PN"DC35"5;
"VDDCR_CPU1_DB53"
$PN"DB53"5;
"VDDCR_CPU1_DB52"
$PN"DB52"5;
"VDDCR_CPU1_DB50"
$PN"DB50"5;
"VDDCR_CPU1_DB49"
$PN"DB49"5;
"VDDCR_CPU1_DB47"
$PN"DB47"5;
"VDDCR_CPU1_DB46"
$PN"DB46"5;
"VDDCR_CPU1_DB44"
$PN"DB44"5;
"VDDCR_CPU1_DB43"
$PN"DB43"5;
"VDDCR_CPU1_DB33"
$PN"DB33"5;
"VDDCR_CPU1_DB32"
$PN"DB32"5;
"VDDCR_CPU1_DB30"
$PN"DB30"5;
"VDDCR_CPU1_DB29"
$PN"DB29"5;
"VDDCR_CPU1_DB27"
$PN"DB27"5;
"VDDCR_CPU1_DB26"
$PN"DB26"5;
"VDDCR_CPU1_DB24"
$PN"DB24"5;
"VDDCR_CPU1_DB23"
$PN"DB23"5;
"VDDCR_CPU1_DA41"
$PN"DA41"5;
"VDDCR_CPU1_DA40"
$PN"DA40"5;
"VDDCR_CPU1_DA36"
$PN"DA36"5;
"VDDCR_CPU1_DA35"
$PN"DA35"5;
"VDDCR_CPU1_CV53"
$PN"CV53"5;
"VDDCR_CPU1_CV52"
$PN"CV52"5;
"VDDCR_CPU1_CV50"
$PN"CV50"5;
"VDDCR_CPU1_CV49"
$PN"CV49"5;
"VDDCR_CPU1_CV47"
$PN"CV47"5;
"VDDCR_CPU1_CV46"
$PN"CV46"5;
"VDDCR_CPU1_CV44"
$PN"CV44"5;
"VDDCR_CPU1_CV43"
$PN"CV43"5;
"VDDCR_CPU1_CV33"
$PN"CV33"5;
"VDDCR_CPU1_CV32"
$PN"CV32"5;
"VDDCR_CPU1_CV30"
$PN"CV30"5;
"VDDCR_CPU1_CV29"
$PN"CV29"5;
"VDDCR_CPU1_CV27"
$PN"CV27"5;
"VDDCR_CPU1_CV26"
$PN"CV26"5;
"VDDCR_CPU1_CV24"
$PN"CV24"5;
"VDDCR_CPU1_CV23"
$PN"CV23"5;
"VDDCR_CPU1_CU41"
$PN"CU41"5;
"VDDCR_CPU1_CU40"
$PN"CU40"5;
"VDDCR_CPU1_CU36"
$PN"CU36"5;
"VDDCR_CPU1_CU35"
$PN"CU35"5;
"VDDCR_CPU1_CP53"
$PN"CP53"5;
"VDDCR_CPU1_CP52"
$PN"CP52"5;
"VDDCR_CPU1_CP50"
$PN"CP50"5;
"VDDCR_CPU1_CP49"
$PN"CP49"5;
"VDDCR_CPU1_CP47"
$PN"CP47"5;
"VDDCR_CPU1_CP46"
$PN"CP46"5;
"VDDCR_CPU1_CP44"
$PN"CP44"5;
"VDDCR_CPU1_CP43"
$PN"CP43"5;
"VDDCR_CPU1_CP33"
$PN"CP33"5;
"VDDCR_CPU1_CP32"
$PN"CP32"5;
"VDDCR_CPU1_CP30"
$PN"CP30"5;
"VDDCR_CPU1_CP29"
$PN"CP29"5;
"VDDCR_CPU1_CP27"
$PN"CP27"5;
"VDDCR_CPU1_CP26"
$PN"CP26"5;
"VDDCR_CPU1_CP24"
$PN"CP24"5;
"VDDCR_CPU1_CP23"
$PN"CP23"5;
"VDDCR_CPU1_CN41"
$PN"CN41"5;
"VDDCR_CPU1_CN40"
$PN"CN40"5;
"VDDCR_CPU1_CN36"
$PN"CN36"5;
"VDDCR_CPU1_CN35"
$PN"CN35"5;
"VDDCR_CPU1_CL47"
$PN"CL47"5;
"VDDCR_CPU1_CL46"
$PN"CL46"5;
"VDDCR_CPU1_CL44"
$PN"CL44"5;
"VDDCR_CPU1_CL43"
$PN"CL43"5;
"VDDCR_CPU1_CL33"
$PN"CL33"5;
"VDDCR_CPU1_CL32"
$PN"CL32"5;
"VDDCR_CPU1_CL30"
$PN"CL30"6;
"VDDCR_CPU1_CL29"
$PN"CL29"6;
"VDDCR_CPU1_CK41"
$PN"CK41"6;
"VDDCR_CPU1_CK40"
$PN"CK40"6;
"VDDCR_CPU1_CK36"
$PN"CK36"6;
"VDDCR_CPU1_CK35"
$PN"CK35"6;
"VDDCR_CPU1_CH53"
$PN"CH53"6;
"VDDCR_CPU1_CH52"
$PN"CH52"6;
"VDDCR_CPU1_CH50"
$PN"CH50"6;
"VDDCR_CPU1_CH49"
$PN"CH49"6;
"VDDCR_CPU1_CH47"
$PN"CH47"6;
"VDDCR_CPU1_CH46"
$PN"CH46"6;
"VDDCR_CPU1_CH44"
$PN"CH44"6;
"VDDCR_CPU1_CH43"
$PN"CH43"6;
"VDDCR_CPU1_CH33"
$PN"CH33"6;
"VDDCR_CPU1_CH32"
$PN"CH32"6;
"VDDCR_CPU1_CH30"
$PN"CH30"6;
"VDDCR_CPU1_CH29"
$PN"CH29"6;
"VDDCR_CPU1_CH27"
$PN"CH27"6;
"VDDCR_CPU1_CH26"
$PN"CH26"6;
"VDDCR_CPU1_CH24"
$PN"CH24"6;
"VDDCR_CPU1_CH23"
$PN"CH23"6;
"VDDCR_CPU1_CG41"
$PN"CG41"6;
"VDDCR_CPU1_CG40"
$PN"CG40"6;
"VDDCR_CPU1_CG36"
$PN"CG36"6;
"VDDCR_CPU1_CG35"
$PN"CG35"6;
"VDDCR_CPU1_CD53"
$PN"CD53"6;
"VDDCR_CPU1_CD52"
$PN"CD52"6;
"VDDCR_CPU1_CD50"
$PN"CD50"6;
"VDDCR_CPU1_CD49"
$PN"CD49"6;
"VDDCR_CPU1_CD47"
$PN"CD47"6;
"VDDCR_CPU1_CD46"
$PN"CD46"6;
"VDDCR_CPU1_CD44"
$PN"CD44"6;
"VDDCR_CPU1_CD43"
$PN"CD43"6;
"VDDCR_CPU1_CD33"
$PN"CD33"6;
"VDDCR_CPU1_CD32"
$PN"CD32"6;
"VDDCR_CPU1_CD30"
$PN"CD30"6;
"VDDCR_CPU1_CD29"
$PN"CD29"6;
"VDDCR_CPU1_CD27"
$PN"CD27"6;
"VDDCR_CPU1_CD26"
$PN"CD26"6;
"VDDCR_CPU1_CD24"
$PN"CD24"6;
"VDDCR_CPU1_CD23"
$PN"CD23"6;
"VDDCR_CPU1_CC41"
$PN"CC41"6;
"VDDCR_CPU1_CC40"
$PN"CC40"6;
"VDDCR_CPU1_CC36"
$PN"CC36"6;
"VDDCR_CPU1_CC35"
$PN"CC35"6;
"VDDCR_CPU1_BY53"
$PN"BY53"6;
"VDDCR_CPU1_BY52"
$PN"BY52"6;
"VDDCR_CPU1_BY50"
$PN"BY50"6;
"VDDCR_CPU1_BY49"
$PN"BY49"6;
"VDDCR_CPU1_BY47"
$PN"BY47"6;
"VDDCR_CPU1_BY46"
$PN"BY46"6;
"VDDCR_CPU1_BY44"
$PN"BY44"6;
"VDDCR_CPU1_BY43"
$PN"BY43"6;
"VDDCR_CPU1_BY33"
$PN"BY33"6;
"VDDCR_CPU1_BY32"
$PN"BY32"6;
"VDDCR_CPU1_BY30"
$PN"BY30"6;
"VDDCR_CPU1_BY29"
$PN"BY29"6;
"VDDCR_CPU1_BY27"
$PN"BY27"6;
"VDDCR_CPU1_BY26"
$PN"BY26"6;
"VDDCR_CPU1_BY24"
$PN"BY24"6;
"VDDCR_CPU1_BY23"
$PN"BY23"6;
"VDDCR_CPU1_BW41"
$PN"BW41"6;
"VDDCR_CPU1_BW40"
$PN"BW40"6;
"VDDCR_CPU1_BW36"
$PN"BW36"6;
"VDDCR_CPU1_BW35"
$PN"BW35"6;
"VDDCR_CPU1_BT53"
$PN"BT53"6;
"VDDCR_CPU1_BT52"
$PN"BT52"6;
"VDDCR_CPU1_BT50"
$PN"BT50"6;
"VDDCR_CPU1_BT49"
$PN"BT49"6;
"VDDCR_CPU1_BT47"
$PN"BT47"6;
"VDDCR_CPU1_BT46"
$PN"BT46"6;
"VDDCR_CPU1_BT44"
$PN"BT44"6;
"VDDCR_CPU1_BT43"
$PN"BT43"6;
"VDDCR_CPU1_BT33"
$PN"BT33"6;
"VDDCR_CPU1_BT32"
$PN"BT32"6;
"VDDCR_CPU1_BT30"
$PN"BT30"6;
"VDDCR_CPU1_BT29"
$PN"BT29"6;
"VDDCR_CPU1_BT27"
$PN"BT27"6;
"VDDCR_CPU1_BT26"
$PN"BT26"6;
"VDDCR_CPU1_BT24"
$PN"BT24"6;
"VDDCR_CPU1_BT23"
$PN"BT23"6;
"VDDCR_CPU1_BR52"
$PN"BR52"6;
"VDDCR_CPU1_BR50"
$PN"BR50"6;
"VDDCR_CPU1_BR48"
$PN"BR48"6;
"VDDCR_CPU1_BR46"
$PN"BR46"6;
"VDDCR_CPU1_BR44"
$PN"BR44"6;
"VDDCR_CPU1_BR42"
$PN"BR42"6;
"VDDCR_CPU1_BR40"
$PN"BR40"6;
"VDDCR_CPU1_BR35"
$PN"BR35"6;
"VDDCR_CPU1_BR33"
$PN"BR33"6;
"VDDCR_CPU1_BR31"
$PN"BR31"6;
"VDDCR_CPU1_BR29"
$PN"BR29"6;
"VDDCR_CPU1_BR27"
$PN"BR27"6;
"VDDCR_CPU1_BR25"
$PN"BR25"6;
"VDDCR_CPU1_BR23"
$PN"BR23"6;
"VDDCR_CPU1_BP49"
$PN"BP49"6;
"VDDCR_CPU1_BP47"
$PN"BP47"6;
"VDDCR_CPU1_BP45"
$PN"BP45"6;
"VDDCR_CPU1_BP43"
$PN"BP43"6;
"VDDCR_CPU1_BP41"
$PN"BP41"6;
"VDDCR_CPU1_BP39"
$PN"BP39"6;
"VDDCR_CPU1_BP36"
$PN"BP36"6;
"VDDCR_CPU1_BP34"
$PN"BP34"6;
"VDDCR_CPU1_BP30"
$PN"BP30"6;
"VDDCR_CPU1_BP26"
$PN"BP26"6;
"VDDCR_CPU1_BN50"
$PN"BN50"6;
"VDDCR_CPU1_BN42"
$PN"BN42"6;
"VDDCR_CPU1_BN31"
$PN"BN31"6;
%"VCC_CORE"
"1","(-2050,6575)","0","pure_quanta_power","I36";
;
HDL_POWER"PVDDIO_P1"
CDS_LIB"pure_quanta_power";
"A"7;
%"UNIVERSAL_POWER"
"1","(-1125,950)","0","pure_quanta_power","I37";
;
HDL_POWER"PVDD18_S5_P1"
CDS_LIB"pure_quanta_power";
"A"1;
%"UNIVERSAL_POWER"
"1","(-1450,950)","0","pure_quanta_power","I38";
;
HDL_POWER"P1V5_BAT"
CDS_LIB"pure_quanta_power";
"A"2;
%"VCC_CORE"
"1","(-3550,6575)","0","pure_quanta_power","I41";
;
HDL_POWER"PVDD11_S3_P1"
CDS_LIB"pure_quanta_power";
"A"8;
%"UNIVERSAL_POWER"
"1","(-3725,2700)","0","pure_quanta_power","I42";
;
HDL_POWER"PVDD18_S5_P1"
CDS_LIB"pure_quanta_power";
"A"9;
%"UNIVERSAL_POWER"
"1","(-3725,1050)","0","pure_quanta_power","I44";
;
HDL_POWER"PVDD_33_S5"
CDS_LIB"pure_quanta_power";
"A"10;
%"GENOA_SP5"
"27","(-2800,3500)","0","pure_quanta","I45";
;
LOCATION"U26"
$SEC"27"
CDS_SEC"27"
VALUE"SOCKET6096_13568-001"
PART_TYPE"SMLF"
MATERIAL"IO"
NEEDS_NO_SIZE"TRUE"
CDS_LMAN_SYM_OUTLINE"-500,3075,500,-3075"
CDS_LIB"pure_quanta"
PART_NUMBER"DGA^6000030";
"VDD_11_S3_CT19"
$PN"CT19"8;
"VDD_11_S3_CT22"
$PN"CT22"8;
"VDD_11_S3_CW4"
$PN"CW4"8;
"VDD_11_S3_CW11"
$PN"CW11"8;
"VDD_11_S3_CW18"
$PN"CW18"8;
"VDD_11_S3_CY22"
$PN"CY22"8;
"VDD_11_S3_DB5"
$PN"DB5"8;
"VDD_11_S3_DB12"
$PN"DB12"8;
"VDD_11_S3_DB19"
$PN"DB19"8;
"VDD_11_S3_DE4"
$PN"DE4"8;
"VDD_11_S3_DE11"
$PN"DE11"8;
"VDD_11_S3_DE18"
$PN"DE18"8;
"VDD_11_S3_DG5"
$PN"DG5"8;
"VDDIO_CT64"
$PN"CT64"7;
"VDDIO_CT71"
$PN"CT71"7;
"VDDIO_CW58"
$PN"CW58"7;
"VDDIO_CW65"
$PN"CW65"7;
"VDDIO_CW72"
$PN"CW72"7;
"VDDIO_CY54"
$PN"CY54"7;
"VDDIO_DB57"
$PN"DB57"7;
"VDDIO_DB64"
$PN"DB64"7;
"VDDIO_DB71"
$PN"DB71"7;
"VDDIO_DE58"
$PN"DE58"7;
"VDDIO_DE65"
$PN"DE65"7;
"VDDIO_DE72"
$PN"DE72"7;
"VDDIO_DG64"
$PN"DG64"7;
"VDDIO_DG71"
$PN"DG71"7;
"VDDBT_RTC_G"
$PN"BN23"13;
"VDDIO_AUDIO"
$PN"BH27"9;
"VDD_33_S5_BP51"
$PN"BP51"10;
"VDD_33_S5_BN52"
$PN"BN52"10;
"VDD_11_S3_CT12"
$PN"CT12"8;
"VDD_18_S5_BB53"
$PN"BB53"9;
"VDD_18_S5_BB51"
$PN"BB51"9;
"VDD_18_S5_BA54"
$PN"BA54"9;
"VDD_18_S5_BA52"
$PN"BA52"9;
"VDD_18_S5_BA50"
$PN"BA50"9;
"VDD_18_S5_AY53"
$PN"AY53"9;
"VDD_18_S5_AY51"
$PN"AY51"9;
"VDD_18_S5_AW54"
$PN"AW54"9;
"VDD_18_S5_AW52"
$PN"AW52"9;
"VDD_18_S5_BC54"
$PN"BC54"9;
"VDD_18_S5_BC52"
$PN"BC52"9;
"VDD_18_S5_AW50"
$PN"AW50"9;
"VDD_18_S5_AV53"
$PN"AV53"9;
"VDD_18_S5_AV51"
$PN"AV51"9;
"VDD_18_S5_AV49"
$PN"AV49"9;
"VDD_18_S5_AU52"
$PN"AU52"9;
"VDD_18_S5_AU50"
$PN"AU50"9;
"VDD_18_S5_AT53"
$PN"AT53"9;
"VDD_18_S5_AT51"
$PN"AT51"9;
"VDD_18_S5_AR54"
$PN"AR54"9;
"VDD_18_S5_AR52"
$PN"AR52"9;
"VDD_18_S5_AU54"
$PN"AU54"9;
"VDD_11_S3_CT5"
$PN"CT5"8;
"VDD_11_S3_CN18"
$PN"CN18"8;
"VDD_11_S3_CN11"
$PN"CN11"8;
"VDD_11_S3_CN4"
$PN"CN4"8;
"VDD_11_S3_CM22"
$PN"CM22"8;
"VDD_11_S3_CK19"
$PN"CK19"8;
"VDD_11_S3_CK12"
$PN"CK12"8;
"VDD_11_S3_CK5"
$PN"CK5"8;
"VDD_11_S3_CJ22"
$PN"CJ22"8;
"VDD_11_S3_CG18"
$PN"CG18"8;
"VDD_11_S3_CG11"
$PN"CG11"8;
"VDD_11_S3_CG4"
$PN"CG4"8;
"VDD_11_S3_CF22"
$PN"CF22"8;
"VDD_11_S3_CD19"
$PN"CD19"8;
"VDD_11_S3_CD12"
$PN"CD12"8;
"VDD_11_S3_CD5"
$PN"CD5"8;
"VDD_11_S3_CB22"
$PN"CB22"8;
"VDD_11_S3_CA18"
$PN"CA18"8;
"VDD_11_S3_CA11"
$PN"CA11"8;
"VDD_11_S3_CA4"
$PN"CA4"8;
"VDD_11_S3_BV22"
$PN"BV22"8;
"VDD_11_S3_BV19"
$PN"BV19"8;
"VDD_11_S3_BV12"
$PN"BV12"8;
"VDD_11_S3_BV5"
$PN"BV5"8;
"VDD_11_S3_BR18"
$PN"BR18"8;
"VDD_11_S3_BR11"
$PN"BR11"8;
"VDD_11_S3_BR4"
$PN"BR4"8;
"VDD_11_S3_BP22"
$PN"BP22"8;
"VDD_11_S3_BN48"
$PN"BN48"8;
"VDD_11_S3_BN44"
$PN"BN44"8;
"VDD_11_S3_BN40"
$PN"BN40"8;
"VDD_11_S3_BN33"
$PN"BN33"8;
"VDD_11_S3_BN29"
$PN"BN29"8;
"VDD_11_S3_BN25"
$PN"BN25"8;
"VDD_11_S3_BM49"
$PN"BM49"8;
"VDD_11_S3_BM47"
$PN"BM47"8;
"VDD_11_S3_BM45"
$PN"BM45"8;
"VDD_11_S3_BM43"
$PN"BM43"8;
"VDD_11_S3_BM41"
$PN"BM41"8;
"VDD_11_S3_BM39"
$PN"BM39"8;
"VDD_11_S3_BM36"
$PN"BM36"8;
"VDD_11_S3_BM34"
$PN"BM34"8;
"VDD_11_S3_BM32"
$PN"BM32"8;
"VDD_11_S3_BM30"
$PN"BM30"8;
"VDD_11_S3_BM28"
$PN"BM28"8;
"VDD_11_S3_BM26"
$PN"BM26"8;
"VDD_11_S3_BM24"
$PN"BM24"8;
"VDD_11_S3_BM22"
$PN"BM22"8;
"VDD_11_S3_BM19"
$PN"BM19"8;
"VDD_11_S3_BM12"
$PN"BM12"8;
"VDD_11_S3_BL48"
$PN"BL48"8;
"VDD_11_S3_BL27"
$PN"BL27"8;
"VDD_11_S3_BL25"
$PN"BL25"8;
"VDD_11_S3_BL23"
$PN"BL23"8;
"VDD_11_S3_BK49"
$PN"BK49"8;
"VDD_11_S3_BK28"
$PN"BK28"8;
"VDD_11_S3_BK26"
$PN"BK26"8;
"VDD_11_S3_BK24"
$PN"BK24"8;
"VDD_11_S3_BK22"
$PN"BK22"8;
"VDD_11_S3_BJ27"
$PN"BJ27"8;
"VDD_11_S3_BJ25"
$PN"BJ25"8;
"VDD_11_S3_BJ23"
$PN"BJ23"8;
"VDD_11_S3_BJ18"
$PN"BJ18"8;
"VDDIO_CT57"
$PN"CT57"7;
"VDDIO_CT54"
$PN"CT54"7;
"VDDIO_CN72"
$PN"CN72"7;
"VDDIO_CN65"
$PN"CN65"7;
"VDDIO_CN58"
$PN"CN58"7;
"VDDIO_CM54"
$PN"CM54"7;
"VDDIO_CK71"
$PN"CK71"7;
"VDDIO_CK64"
$PN"CK64"7;
"VDDIO_CK57"
$PN"CK57"7;
"VDDIO_CJ54"
$PN"CJ54"7;
"VDDIO_CG72"
$PN"CG72"7;
"VDDIO_CG65"
$PN"CG65"7;
"VDDIO_CG58"
$PN"CG58"7;
"VDDIO_CF54"
$PN"CF54"7;
"VDDIO_CD71"
$PN"CD71"7;
"VDDIO_CD64"
$PN"CD64"7;
"VDDIO_CD57"
$PN"CD57"7;
"VDDIO_CB54"
$PN"CB54"7;
"VDDIO_CA72"
$PN"CA72"7;
"VDDIO_CA65"
$PN"CA65"7;
"VDDIO_CA58"
$PN"CA58"7;
"VDDIO_BV71"
$PN"BV71"7;
"VDDIO_BV64"
$PN"BV64"7;
"VDDIO_BV57"
$PN"BV57"7;
"VDDIO_BV54"
$PN"BV54"7;
"VDDIO_BR72"
$PN"BR72"7;
"VDDIO_BR65"
$PN"BR65"7;
"VDDIO_BR58"
$PN"BR58"7;
"VDDIO_BN54"
$PN"BN54"7;
"VDDIO_BM71"
$PN"BM71"7;
"VDDIO_BM64"
$PN"BM64"7;
"VDDIO_BM57"
$PN"BM57"7;
"VDDIO_BM53"
$PN"BM53"7;
"VDDIO_BM51"
$PN"BM51"7;
"VDDIO_BL54"
$PN"BL54"7;
"VDDIO_BL52"
$PN"BL52"7;
"VDDIO_BL50"
$PN"BL50"7;
"VDDIO_BK53"
$PN"BK53"7;
"VDDIO_BK51"
$PN"BK51"7;
"VDDIO_BJ72"
$PN"BJ72"7;
"VDDIO_BJ65"
$PN"BJ65"7;
"VDDIO_BJ58"
$PN"BJ58"7;
"VDDIO_BJ54"
$PN"BJ54"7;
"VDDIO_BJ52"
$PN"BJ52"7;
"VDDIO_BJ50"
$PN"BJ50"7;
"VDDIO_BH53"
$PN"BH53"7;
"VDDIO_BH51"
$PN"BH51"7;
"VDDIO_BG54"
$PN"BG54"7;
"VDDIO_BG52"
$PN"BG52"7;
"VDDIO_BG50"
$PN"BG50"7;
"VDDIO_BF71"
$PN"BF71"7;
"VDDIO_BF64"
$PN"BF64"7;
"VDDIO_BF57"
$PN"BF57"7;
"VDDIO_BF53"
$PN"BF53"7;
"VDDIO_BF51"
$PN"BF51"7;
"VDDIO_BD54"
$PN"BD54"7;
"VDDIO_BD52"
$PN"BD52"7;
"VDDIO_BD50"
$PN"BD50"7;
"VDDIO_BA72"
$PN"BA72"7;
"VDDIO_BA65"
$PN"BA65"7;
"VDDIO_BA58"
$PN"BA58"7;
"VDDIO_AV71"
$PN"AV71"7;
"VDDIO_AV64"
$PN"AV64"7;
"VDDIO_AV57"
$PN"AV57"7;
"VDDIO_AR72"
$PN"AR72"7;
"VDDIO_AR65"
$PN"AR65"7;
"VDDIO_AR58"
$PN"AR58"7;
"VDDIO_AM71"
$PN"AM71"7;
"VDDIO_AM64"
$PN"AM64"7;
"VDDIO_AM57"
$PN"AM57"7;
"VDDIO_AM54"
$PN"AM54"7;
"VDDIO_AJ72"
$PN"AJ72"7;
"VDDIO_AJ65"
$PN"AJ65"7;
"VDDIO_AJ58"
$PN"AJ58"7;
"VDDIO_AH54"
$PN"AH54"7;
"VDDIO_AF71"
$PN"AF71"7;
"VDDIO_AF64"
$PN"AF64"7;
"VDDIO_AF57"
$PN"AF57"7;
"VDDIO_AD54"
$PN"AD54"7;
"VDDIO_AC72"
$PN"AC72"7;
"VDDIO_AC65"
$PN"AC65"7;
"VDDIO_AC58"
$PN"AC58"7;
"VDDIO_AA54"
$PN"AA54"7;
"VDDIO_Y71"
$PN"Y71"7;
"VDDIO_Y64"
$PN"Y64"7;
"VDDIO_Y57"
$PN"Y57"7;
"VDDIO_V54"
$PN"V54"7;
"VDDIO_U72"
$PN"U72"7;
"VDDIO_U65"
$PN"U65"7;
"VDDIO_U58"
$PN"U58"7;
"VDDIO_P71"
$PN"P71"7;
"VDDIO_P64"
$PN"P64"7;
"VDDIO_P57"
$PN"P57"7;
"VDDIO_P54"
$PN"P54"7;
"VDDIO_L72"
$PN"L72"7;
"VDDIO_L65"
$PN"L65"7;
"VDDIO_L58"
$PN"L58"7;
"VDDIO_K54"
$PN"K54"7;
"VDDIO_H71"
$PN"H71"7;
"VDDIO_H64"
$PN"H64"7;
"VDDIO_H57"
$PN"H57"7;
%"GENOA_SP5"
"23","(-875,4325)","0","pure_quanta","I46";
;
LOCATION"U26"
$SEC"23"
CDS_SEC"23"
VALUE"SOCKET6096_13568-001"
MATERIAL"IO"
PART_TYPE"SMLF"
NEEDS_NO_SIZE"TRUE"
CDS_LMAN_SYM_OUTLINE"-550,2000,550,-2000"
CDS_LIB"pure_quanta"
PART_NUMBER"DGA^6000030";
"TEST6_X3D6"
$PN"B36"0;
"TEST4_CCD15"
$PN"C23"0;
"TEST4_CCD12"
$PN"C58"0;
"TEST5_CCD12"
$PN"C59"0;
"TEST5_CCD15"
$PN"D23"0;
"TEST4_CCD14"
$PN"DF41"0;
"TEST5_CCD14"
$PN"DG42"0;
"TEST4_CCD13"
$PN"DH13"0;
"TEST5_CCD13"
$PN"DH14"0;
"TEST6_X3D7"
$PN"DJ57"0;
"RSVD_A60"
$PN"A60"0;
"RSVD_BD7"
$PN"BD7"0;
"RSVD_D36"
$PN"D36"0;
"RSVD_BD58"
$PN"BD58"0;
"RSVD_BD55"
$PN"BD55"0;
"RSVD_A54"
$PN"A54"0;
"RSVD_A51"
$PN"A51"0;
"RSVD_A50"
$PN"A50"0;
"RSVD_A48"
$PN"A48"0;
"RSVD_C53"
$PN"C53"0;
"RSVD_A45"
$PN"A45"0;
"RSVD_C35"
$PN"C35"0;
"RSVD_D65"
$PN"D65"0;
"RSVD_A42"
$PN"A42"0;
"RSVD_C34"
$PN"C34"0;
"RSVD_D62"
$PN"D62"0;
"RSVD_BD21"
$PN"BD21"0;
"RSVD_A41"
$PN"A41"0;
"RSVD_C31"
$PN"C31"0;
"RSVD_D58"
$PN"D58"0;
"RSVD_BD18"
$PN"BD18"0;
"RSVD_DJ4"
$PN"DJ4"0;
"RSVD_A35"
$PN"A35"0;
"RSVD_B40"
$PN"B40"0;
"RSVD_BD14"
$PN"BD14"0;
"RSVD_DH21"
$PN"DH21"0;
"RSVD_A31"
$PN"A31"0;
"RSVD_D34"
$PN"D34"0;
"RSVD_BD11"
$PN"BD11"0;
"RSVD_DH17"
$PN"DH17"0;
"RSVD_A59"
$PN"A59"0;
"RSVD_D22"
$PN"D22"0;
"RSVD_DG17"
$PN"DG17"0;
"RSVD_A57"
$PN"A57"0;
"RSVD_D11"
$PN"D11"0;
"RSVD_BD4"
$PN"BD4"0;
"RSVD_BD72"
$PN"BD72"0;
"RSVD_A56"
$PN"A56"0;
"RSVD_D8"
$PN"D8"0;
"RSVD_E36"
$PN"E36"0;
"RSVD_BD69"
$PN"BD69"0;
"RSVD_A55"
$PN"A55"0;
"RSVD_D4"
$PN"D4"0;
"RSVD_E33"
$PN"E33"0;
"RSVD_BD65"
$PN"BD65"0;
"RSVD_C54"
$PN"C54"0;
"RSVD_D72"
$PN"D72"0;
"RSVD_BD62"
$PN"BD62"0;
%"VCC_CORE"
"1","(-3825,6250)","0","pure_quanta_power","I47";
;
HDL_POWER"PVDDCR_SOC_P1"
CDS_LIB"pure_quanta_power";
"A"11;
%"VCC_CORE"
"1","(-5125,6250)","0","pure_quanta_power","I48";
;
HDL_POWER"PVDDCR_SOC_P1"
CDS_LIB"pure_quanta_power";
"A"12;
%"GENOA_SP5"
"26","(-4475,4675)","0","pure_quanta","I49";
;
LOCATION"U26"
$SEC"26"
CDS_SEC"26"
VALUE"SOCKET6096_13568-001"
MATERIAL"IO"
PART_TYPE"SMLF"
NEEDS_NO_SIZE"TRUE"
CDS_LMAN_SYM_OUTLINE"-450,1650,450,-1650"
CDS_LIB"pure_quanta"
PART_NUMBER"DGA^6000030";
"VDDCR_SOC_BG22"
$PN"BG22"11;
"VDDCR_SOC_BG24"
$PN"BG24"11;
"VDDCR_SOC_BG26"
$PN"BG26"11;
"VDDCR_SOC_BG28"
$PN"BG28"11;
"VDDCR_SOC_BG48"
$PN"BG48"11;
"VDDCR_SOC_BH23"
$PN"BH23"11;
"VDDCR_SOC_BH25"
$PN"BH25"11;
"VDDCR_SOC_BH48"
$PN"BH48"11;
"VDDCR_SOC_BJ4"
$PN"BJ4"11;
"VDDCR_SOC_BJ11"
$PN"BJ11"11;
"VDDCR_SOC_BJ48"
$PN"BJ48"11;
"VDDCR_SOC_BM5"
$PN"BM5"11;
"VDDCR_SOC_BF48"
$PN"BF48"11;
"VDDCR_SOC_BF27"
$PN"BF27"11;
"VDDCR_SOC_BF25"
$PN"BF25"11;
"VDDCR_SOC_BF23"
$PN"BF23"11;
"VDDCR_SOC_BD48"
$PN"BD48"11;
"VDDCR_SOC_BD28"
$PN"BD28"11;
"VDDCR_SOC_BD26"
$PN"BD26"11;
"VDDCR_SOC_BD24"
$PN"BD24"11;
"VDDCR_SOC_BD22"
$PN"BD22"11;
"VDDCR_SOC_BD19"
$PN"BD19"11;
"VDDCR_SOC_BD12"
$PN"BD12"11;
"VDDCR_SOC_BD5"
$PN"BD5"11;
"VDDCR_SOC_BC48"
$PN"BC48"11;
"VDDCR_SOC_BC27"
$PN"BC27"11;
"VDDCR_SOC_BC25"
$PN"BC25"11;
"VDDCR_SOC_BC23"
$PN"BC23"11;
"VDDCR_SOC_BB49"
$PN"BB49"11;
"VDDCR_SOC_BB28"
$PN"BB28"11;
"VDDCR_SOC_BB26"
$PN"BB26"11;
"VDDCR_SOC_BB24"
$PN"BB24"11;
"VDDCR_SOC_BB22"
$PN"BB22"11;
"VDDCR_SOC_BA48"
$PN"BA48"11;
"VDDCR_SOC_BA27"
$PN"BA27"11;
"VDDCR_SOC_BA25"
$PN"BA25"11;
"VDDCR_SOC_BA23"
$PN"BA23"11;
"VDDCR_SOC_BA18"
$PN"BA18"11;
"VDDCR_SOC_BA11"
$PN"BA11"11;
"VDDCR_SOC_BA4"
$PN"BA4"11;
"VDDCR_SOC_AY49"
$PN"AY49"11;
"VDDCR_SOC_AY28"
$PN"AY28"11;
"VDDCR_SOC_AY26"
$PN"AY26"11;
"VDDCR_SOC_AY24"
$PN"AY24"11;
"VDDCR_SOC_AY22"
$PN"AY22"11;
"VDDCR_SOC_AW48"
$PN"AW48"11;
"VDDCR_SOC_AW27"
$PN"AW27"11;
"VDDCR_SOC_AW25"
$PN"AW25"11;
"VDDCR_SOC_AW23"
$PN"AW23"11;
"VDDCR_SOC_AV47"
$PN"AV47"11;
"VDDCR_SOC_AV45"
$PN"AV45"11;
"VDDCR_SOC_AV43"
$PN"AV43"11;
"VDDCR_SOC_AV41"
$PN"AV41"12;
"VDDCR_SOC_AV39"
$PN"AV39"12;
"VDDCR_SOC_AV36"
$PN"AV36"12;
"VDDCR_SOC_AV34"
$PN"AV34"12;
"VDDCR_SOC_AV32"
$PN"AV32"12;
"VDDCR_SOC_AV30"
$PN"AV30"12;
"VDDCR_SOC_AV28"
$PN"AV28"12;
"VDDCR_SOC_AV26"
$PN"AV26"12;
"VDDCR_SOC_AV24"
$PN"AV24"12;
"VDDCR_SOC_AV22"
$PN"AV22"12;
"VDDCR_SOC_AV19"
$PN"AV19"12;
"VDDCR_SOC_AV12"
$PN"AV12"12;
"VDDCR_SOC_AV5"
$PN"AV5"12;
"VDDCR_SOC_AU40"
$PN"AU40"12;
"VDDCR_SOC_AU35"
$PN"AU35"12;
"VDDCR_SOC_AU31"
$PN"AU31"12;
"VDDCR_SOC_AU27"
$PN"AU27"12;
"VDDCR_SOC_AU23"
$PN"AU23"12;
"VDDCR_SOC_AT22"
$PN"AT22"12;
"VDDCR_SOC_AR18"
$PN"AR18"12;
"VDDCR_SOC_AR11"
$PN"AR11"12;
"VDDCR_SOC_AR4"
$PN"AR4"12;
"VDDCR_SOC_AM22"
$PN"AM22"12;
"VDDCR_SOC_AM19"
$PN"AM19"12;
"VDDCR_SOC_AM12"
$PN"AM12"12;
"VDDCR_SOC_AM5"
$PN"AM5"12;
"VDDCR_SOC_AJ18"
$PN"AJ18"12;
"VDDCR_SOC_AJ11"
$PN"AJ11"12;
"VDDCR_SOC_AJ4"
$PN"AJ4"12;
"VDDCR_SOC_AH22"
$PN"AH22"12;
"VDDCR_SOC_AF19"
$PN"AF19"12;
"VDDCR_SOC_AF12"
$PN"AF12"12;
"VDDCR_SOC_AF5"
$PN"AF5"12;
"VDDCR_SOC_AD22"
$PN"AD22"12;
"VDDCR_SOC_AC18"
$PN"AC18"12;
"VDDCR_SOC_AC11"
$PN"AC11"12;
"VDDCR_SOC_AC4"
$PN"AC4"12;
"VDDCR_SOC_AA22"
$PN"AA22"12;
"VDDCR_SOC_Y19"
$PN"Y19"12;
"VDDCR_SOC_Y12"
$PN"Y12"12;
"VDDCR_SOC_Y5"
$PN"Y5"12;
"VDDCR_SOC_V22"
$PN"V22"12;
"VDDCR_SOC_U18"
$PN"U18"12;
"VDDCR_SOC_U11"
$PN"U11"12;
"VDDCR_SOC_U4"
$PN"U4"12;
"VDDCR_SOC_P22"
$PN"P22"12;
"VDDCR_SOC_P19"
$PN"P19"12;
"VDDCR_SOC_P12"
$PN"P12"12;
"VDDCR_SOC_P5"
$PN"P5"12;
"VDDCR_SOC_L18"
$PN"L18"12;
"VDDCR_SOC_L11"
$PN"L11"12;
"VDDCR_SOC_L4"
$PN"L4"12;
"VDDCR_SOC_K22"
$PN"K22"12;
"VDDCR_SOC_H19"
$PN"H19"12;
"VDDCR_SOC_H12"
$PN"H12"12;
"VDDCR_SOC_H5"
$PN"H5"12;
"VDDCR_SOC_E11"
$PN"E11"12;
"VDDCR_SOC_E4"
$PN"E4"12;
"VDDCR_SOC_C4"
$PN"C4"12;
"VDDCR_SOC_B5"
$PN"B5"12;
%"Q_RES"
"2","(-1125,725)","0","pure_quanta","I51";
;
LOCATION"R374"
$SEC"1"
CDS_SEC"1"
WATTAGE"1/16W"
MATERIAL"CHIP"
TOLERANCE"5%"
VALUE"0"
PACK_TYPE"0402LF"
BOM_COST"MEM"
CDS_LIB"pure_quanta"
PART_NUMBER"CS00002JB13";
"A"
$PN"1"1;
"B"
$PN"2"13;
%"Q_RES"
"2","(-1450,725)","0","pure_quanta","I52";
;
LOCATION"R373"
$SEC"1"
CDS_SEC"1"
WATTAGE"1/16W"
MATERIAL"EMPTY"
TOLERANCE"5%"
VALUE"0"
PACK_TYPE"0402LF"
BOM_COST"MEM"
CDS_LIB"pure_quanta"
PART_NUMBER"CS00002JB13";
"A"
$PN"1"2;
"B"
$PN"2"13;
END.
